# S9S_MB_2U (Grand Teton) — schematic netlist excerpt (pin names and nets, part order shuffled) for the footprints in the layout excerpt that follows; sources: Cadence DE-HDL packaged netlist, KiCad conversion of 03242023_DA0F0TMBIJ0_F0T_Motherboard_J_brd_V01_OCP.brd

PC308_P0_1  Q_CAP  100NF 50V 10% X7R  pkg C0402  page 267 : A = PVCCIN_CPU0 ; B = GND
R375  Q_RES  10K 1% CHIP  pkg 0402LF  page 198 : A = FM_SPI_3V3_1V8_VOLTAGE ; B = GND

(kicad_pcb
	(version 20260206)
	(generator "pcbnew")
	(generator_version "10.0")
	(general
		(thickness 1.6)
		(legacy_teardrops no)
	)
	(paper "A4")
	(title_block
		(title "03242023_DA0F0TMBIJ0_F0T_Motherboard_J_brd_V01_OCP.brd")
		(comment 1 "Grand Teton / footprints 5127-5128 of 6105")
	)
	(layers
		(0 "F.Cu" signal "TOP")
		(4 "In1.Cu" signal "GND")
		(6 "In2.Cu" signal "IN1")
		(8 "In3.Cu" signal "GND1")
		(10 "In4.Cu" signal "IN2")
		(12 "In5.Cu" signal "GND2")
		(14 "In6.Cu" signal "IN3")
		(16 "In7.Cu" signal "GND3")
		(18 "In8.Cu" signal "VCC")
		(20 "In9.Cu" signal "VCC1")
		(22 "In10.Cu" signal "GND4")
		(24 "In11.Cu" signal "IN4")
		(26 "In12.Cu" signal "GND5")
		(28 "In13.Cu" signal "IN5")
		(30 "In14.Cu" signal "GND6")
		(32 "In15.Cu" signal "IN6")
		(34 "In16.Cu" signal "GND7")
		(2 "B.Cu" signal "BOTTOM")
		(9 "F.Adhes" user "F.Adhesive")
		(11 "B.Adhes" user "B.Adhesive")
		(13 "F.Paste" user "Package Geometry/Pastemask Top")
		(15 "B.Paste" user "Package Geometry/Pastemask Bottom")
		(5 "F.SilkS" user "Ref Des/Silkscreen Top")
		(7 "B.SilkS" user "Ref Des/Silkscreen Bottom")
		(1 "F.Mask" user "Board Geometry/Soldermask Top")
		(3 "B.Mask" user "Board Geometry/Soldermask Bottom")
		(17 "Dwgs.User" user "User.Drawings")
		(19 "Cmts.User" user "User.Comments")
		(21 "Eco1.User" user "User.Eco1")
		(23 "Eco2.User" user "User.Eco2")
		(25 "Edge.Cuts" user "Board Geometry/Outline")
		(27 "Margin" user)
		(31 "F.CrtYd" user "Package Geometry/Place Bound Top")
		(29 "B.CrtYd" user "Package Geometry/Place Bound Bottom")
		(35 "F.Fab" user "Ref Des/Assembly Top")
		(33 "B.Fab" user "Ref Des/Assembly Bottom")
	)
	(footprint ""
		(layer "B.Cu")
		(at 366.992408 -325.110094 -90)
		(property "Reference" "PC308_P0_1"
			(at 0 0 90)
			(layer "B.SilkS")
			(hide yes)
			(effects
				(font
					(size 1.27 1.27)
				)
				(justify mirror)
			)
		)
		(property "Value" ""
			(at 0 0 90)
			(layer "B.Fab")
			(effects
				(font
					(size 1.27 1.27)
				)
				(justify mirror)
			)
		)
		(duplicate_pad_numbers_are_jumpers no)
		(fp_line
			(start -0.7874 0.4064)
			(end 0.7874 0.4064)
			(stroke
				(width 0.1524)
				(type default)
			)
			(layer "B.SilkS")
		)
		(fp_line
			(start 0.7874 0.4064)
			(end 0.7874 -0.4064)
			(stroke
				(width 0.1524)
				(type default)
			)
			(layer "B.SilkS")
		)
		(fp_line
			(start -0.7874 -0.4064)
			(end -0.7874 0.4064)
			(stroke
				(width 0.1524)
				(type default)
			)
			(layer "B.SilkS")
		)
		(fp_line
			(start 0.7874 -0.4064)
			(end -0.7874 -0.4064)
			(stroke
				(width 0.1524)
				(type default)
			)
			(layer "B.SilkS")
		)
		(fp_line
			(start -0.67945 0.3048)
			(end -0.120396 0.3048)
			(stroke
				(width 0.1)
				(type default)
			)
			(layer "B.Fab")
		)
		(fp_line
			(start -0.120396 0.3048)
			(end -0.120396 0.2794)
			(stroke
				(width 0.1)
				(type default)
			)
			(layer "B.Fab")
		)
		(fp_line
			(start 0.12065 0.3048)
			(end 0.67945 0.3048)
			(stroke
				(width 0.1)
				(type default)
			)
			(layer "B.Fab")
		)
		(fp_line
			(start 0.67945 0.3048)
			(end 0.67945 -0.305054)
			(stroke
				(width 0.1)
				(type default)
			)
			(layer "B.Fab")
		)
		(fp_line
			(start -0.120396 0.2794)
			(end 0.12065 0.2794)
			(stroke
				(width 0.1)
				(type default)
			)
			(layer "B.Fab")
		)
		(fp_line
			(start 0.12065 0.2794)
			(end 0.12065 0.3048)
			(stroke
				(width 0.1)
				(type default)
			)
			(layer "B.Fab")
		)
		(fp_line
			(start -0.12065 -0.2794)
			(end -0.12065 -0.3048)
			(stroke
				(width 0.1)
				(type default)
			)
			(layer "B.Fab")
		)
		(fp_line
			(start 0.12065 -0.2794)
			(end -0.12065 -0.2794)
			(stroke
				(width 0.1)
				(type default)
			)
			(layer "B.Fab")
		)
		(fp_line
			(start -0.67945 -0.3048)
			(end -0.67945 0.3048)
			(stroke
				(width 0.1)
				(type default)
			)
			(layer "B.Fab")
		)
		(fp_line
			(start -0.12065 -0.3048)
			(end -0.67945 -0.3048)
			(stroke
				(width 0.1)
				(type default)
			)
			(layer "B.Fab")
		)
		(fp_line
			(start 0.12065 -0.305054)
			(end 0.12065 -0.2794)
			(stroke
				(width 0.1)
				(type default)
			)
			(layer "B.Fab")
		)
		(fp_line
			(start 0.67945 -0.305054)
			(end 0.12065 -0.305054)
			(stroke
				(width 0.1)
				(type default)
			)
			(layer "B.Fab")
		)
		(pad "1" smd circle
			(at 0.40005 0 90)
			(size 0 0)
			(layers "B.Cu" "B.Mask" "B.Paste")
			(net "PVCCIN_CPU0")
		)
		(pad "2" smd circle
			(at -0.40005 0 90)
			(size 0 0)
			(layers "B.Cu" "B.Mask" "B.Paste")
			(net "GND")
		)
	)
	(footprint ""
		(layer "B.Cu")
		(at 331.146912 -32.71266 90)
		(property "Reference" "R375"
			(at 0 0 90)
			(layer "B.SilkS")
			(hide yes)
			(effects
				(font
					(size 1.27 1.27)
				)
				(justify mirror)
			)
		)
		(property "Value" ""
			(at 0 0 90)
			(layer "B.Fab")
			(effects
				(font
					(size 1.27 1.27)
				)
				(justify mirror)
			)
		)
		(duplicate_pad_numbers_are_jumpers no)
		(fp_line
			(start 0.7874 -0.4064)
			(end -0.7874 -0.4064)
			(stroke
				(width 0.1524)
				(type default)
			)
			(layer "B.SilkS")
		)
		(fp_line
			(start -0.7874 -0.4064)
			(end -0.7874 0.4064)
			(stroke
				(width 0.1524)
				(type default)
			)
			(layer "B.SilkS")
		)
		(fp_line
			(start 0.7874 0.4064)
			(end 0.7874 -0.4064)
			(stroke
				(width 0.1524)
				(type default)
			)
			(layer "B.SilkS")
		)
		(fp_line
			(start -0.7874 0.4064)
			(end 0.7874 0.4064)
			(stroke
				(width 0.1524)
				(type default)
			)
			(layer "B.SilkS")
		)
		(fp_line
			(start 0.67945 -0.305054)
			(end 0.12065 -0.305054)
			(stroke
				(width 0.1)
				(type default)
			)
			(layer "B.Fab")
		)
		(fp_line
			(start 0.12065 -0.305054)
			(end 0.12065 -0.2794)
			(stroke
				(width 0.1)
				(type default)
			)
			(layer "B.Fab")
		)
		(fp_line
			(start -0.12065 -0.3048)
			(end -0.67945 -0.3048)
			(stroke
				(width 0.1)
				(type default)
			)
			(layer "B.Fab")
		)
		(fp_line
			(start -0.67945 -0.3048)
			(end -0.67945 0.3048)
			(stroke
				(width 0.1)
				(type default)
			)
			(layer "B.Fab")
		)
		(fp_line
			(start 0.12065 -0.2794)
			(end -0.12065 -0.2794)
			(stroke
				(width 0.1)
				(type default)
			)
			(layer "B.Fab")
		)
		(fp_line
			(start -0.12065 -0.2794)
			(end -0.12065 -0.3048)
			(stroke
				(width 0.1)
				(type default)
			)
			(layer "B.Fab")
		)
		(fp_line
			(start 0.12065 0.2794)
			(end 0.12065 0.3048)
			(stroke
				(width 0.1)
				(type default)
			)
			(layer "B.Fab")
		)
		(fp_line
			(start -0.120396 0.2794)
			(end 0.12065 0.2794)
			(stroke
				(width 0.1)
				(type default)
			)
			(layer "B.Fab")
		)
		(fp_line
			(start 0.67945 0.3048)
			(end 0.67945 -0.305054)
			(stroke
				(width 0.1)
				(type default)
			)
			(layer "B.Fab")
		)
		(fp_line
			(start 0.12065 0.3048)
			(end 0.67945 0.3048)
			(stroke
				(width 0.1)
				(type default)
			)
			(layer "B.Fab")
		)
		(fp_line
			(start -0.120396 0.3048)
			(end -0.120396 0.2794)
			(stroke
				(width 0.1)
				(type default)
			)
			(layer "B.Fab")
		)
		(fp_line
			(start -0.67945 0.3048)
			(end -0.120396 0.3048)
			(stroke
				(width 0.1)
				(type default)
			)
			(layer "B.Fab")
		)
		(pad "1" smd circle
			(at 0.40005 0 270)
			(size 0 0)
			(layers "B.Cu" "B.Mask" "B.Paste")
			(net "FM_SPI_3V3_1V8_VOLTAGE")
		)
		(pad "2" smd circle
			(at -0.40005 0 270)
			(size 0 0)
			(layers "B.Cu" "B.Mask" "B.Paste")
			(net "GND")
		)
	)
)
